# S9S_MB_2U (Grand Teton) — schematic netlist excerpt (pin names and nets, part order shuffled) for the footprints in the layout excerpt that follows; sources: Cadence DE-HDL packaged netlist, KiCad conversion of 03242023_DA0F0TMBIJ0_F0T_Motherboard_J_brd_V01_OCP.brd

C2030  Q_CAP  18PF 50V 5% C0G  pkg 0402  page 152 : A = USB_HUB_XTAL_OUT ; B = GND
C1998  Q_CAP  0.1UF 25V 10% X7R  pkg 0402  page 194 : A = P3V3_E1S_0 ; B = GND

(kicad_pcb
	(version 20260206)
	(generator "pcbnew")
	(generator_version "10.0")
	(general
		(thickness 1.6)
		(legacy_teardrops no)
	)
	(paper "A4")
	(title_block
		(title "03242023_DA0F0TMBIJ0_F0T_Motherboard_J_brd_V01_OCP.brd")
		(comment 1 "Grand Teton / footprints 823-824 of 6105")
	)
	(layers
		(0 "F.Cu" signal "TOP")
		(4 "In1.Cu" signal "GND")
		(6 "In2.Cu" signal "IN1")
		(8 "In3.Cu" signal "GND1")
		(10 "In4.Cu" signal "IN2")
		(12 "In5.Cu" signal "GND2")
		(14 "In6.Cu" signal "IN3")
		(16 "In7.Cu" signal "GND3")
		(18 "In8.Cu" signal "VCC")
		(20 "In9.Cu" signal "VCC1")
		(22 "In10.Cu" signal "GND4")
		(24 "In11.Cu" signal "IN4")
		(26 "In12.Cu" signal "GND5")
		(28 "In13.Cu" signal "IN5")
		(30 "In14.Cu" signal "GND6")
		(32 "In15.Cu" signal "IN6")
		(34 "In16.Cu" signal "GND7")
		(2 "B.Cu" signal "BOTTOM")
		(9 "F.Adhes" user "F.Adhesive")
		(11 "B.Adhes" user "B.Adhesive")
		(13 "F.Paste" user "Package Geometry/Pastemask Top")
		(15 "B.Paste" user "Package Geometry/Pastemask Bottom")
		(5 "F.SilkS" user "Ref Des/Silkscreen Top")
		(7 "B.SilkS" user "Ref Des/Silkscreen Bottom")
		(1 "F.Mask" user "Board Geometry/Soldermask Top")
		(3 "B.Mask" user "Board Geometry/Soldermask Bottom")
		(17 "Dwgs.User" user "User.Drawings")
		(19 "Cmts.User" user "User.Comments")
		(21 "Eco1.User" user "User.Eco1")
		(23 "Eco2.User" user "User.Eco2")
		(25 "Edge.Cuts" user "Board Geometry/Outline")
		(27 "Margin" user)
		(31 "F.CrtYd" user "Package Geometry/Place Bound Top")
		(29 "B.CrtYd" user "Package Geometry/Place Bound Bottom")
		(35 "F.Fab" user "Ref Des/Assembly Top")
		(33 "B.Fab" user "Ref Des/Assembly Bottom")
	)
	(footprint ""
		(layer "F.Cu")
		(at 221.67088 -42.255948)
		(property "Reference" "C1998"
			(at 0 0 0)
			(layer "F.SilkS")
			(hide yes)
			(effects
				(font
					(size 1.27 1.27)
				)
			)
		)
		(property "Value" ""
			(at 0 0 0)
			(layer "F.Fab")
			(effects
				(font
					(size 1.27 1.27)
				)
			)
		)
		(duplicate_pad_numbers_are_jumpers no)
		(fp_line
			(start -0.7874 -0.4064)
			(end 0.7874 -0.4064)
			(stroke
				(width 0.1524)
				(type default)
			)
			(layer "F.SilkS")
		)
		(fp_line
			(start -0.7874 0.4064)
			(end -0.7874 -0.4064)
			(stroke
				(width 0.1524)
				(type default)
			)
			(layer "F.SilkS")
		)
		(fp_line
			(start 0.7874 -0.4064)
			(end 0.7874 0.4064)
			(stroke
				(width 0.1524)
				(type default)
			)
			(layer "F.SilkS")
		)
		(fp_line
			(start 0.7874 0.4064)
			(end -0.7874 0.4064)
			(stroke
				(width 0.1524)
				(type default)
			)
			(layer "F.SilkS")
		)
		(fp_line
			(start -0.67945 -0.305054)
			(end -0.12065 -0.305054)
			(stroke
				(width 0.1)
				(type default)
			)
			(layer "F.Fab")
		)
		(fp_line
			(start -0.67945 0.3048)
			(end -0.67945 -0.305054)
			(stroke
				(width 0.1)
				(type default)
			)
			(layer "F.Fab")
		)
		(fp_line
			(start -0.12065 -0.305054)
			(end -0.12065 -0.2794)
			(stroke
				(width 0.1)
				(type default)
			)
			(layer "F.Fab")
		)
		(fp_line
			(start -0.12065 -0.2794)
			(end 0.12065 -0.2794)
			(stroke
				(width 0.1)
				(type default)
			)
			(layer "F.Fab")
		)
		(fp_line
			(start -0.12065 0.2794)
			(end -0.12065 0.3048)
			(stroke
				(width 0.1)
				(type default)
			)
			(layer "F.Fab")
		)
		(fp_line
			(start -0.12065 0.3048)
			(end -0.67945 0.3048)
			(stroke
				(width 0.1)
				(type default)
			)
			(layer "F.Fab")
		)
		(fp_line
			(start 0.120396 0.2794)
			(end -0.12065 0.2794)
			(stroke
				(width 0.1)
				(type default)
			)
			(layer "F.Fab")
		)
		(fp_line
			(start 0.120396 0.3048)
			(end 0.120396 0.2794)
			(stroke
				(width 0.1)
				(type default)
			)
			(layer "F.Fab")
		)
		(fp_line
			(start 0.12065 -0.3048)
			(end 0.67945 -0.3048)
			(stroke
				(width 0.1)
				(type default)
			)
			(layer "F.Fab")
		)
		(fp_line
			(start 0.12065 -0.2794)
			(end 0.12065 -0.3048)
			(stroke
				(width 0.1)
				(type default)
			)
			(layer "F.Fab")
		)
		(fp_line
			(start 0.67945 -0.3048)
			(end 0.67945 0.3048)
			(stroke
				(width 0.1)
				(type default)
			)
			(layer "F.Fab")
		)
		(fp_line
			(start 0.67945 0.3048)
			(end 0.120396 0.3048)
			(stroke
				(width 0.1)
				(type default)
			)
			(layer "F.Fab")
		)
		(pad "1" smd circle
			(at -0.40005 0)
			(size 0 0)
			(layers "F.Cu" "F.Mask" "F.Paste")
			(net "P3V3_E1S_0")
		)
		(pad "2" smd circle
			(at 0.40005 0)
			(size 0 0)
			(layers "F.Cu" "F.Mask" "F.Paste")
			(net "GND")
		)
	)
	(footprint ""
		(layer "F.Cu")
		(at 9.29513 -98.184208 -90)
		(property "Reference" "C2030"
			(at 0 0 270)
			(layer "F.SilkS")
			(hide yes)
			(effects
				(font
					(size 1.27 1.27)
				)
			)
		)
		(property "Value" ""
			(at 0 0 270)
			(layer "F.Fab")
			(effects
				(font
					(size 1.27 1.27)
				)
			)
		)
		(duplicate_pad_numbers_are_jumpers no)
		(fp_line
			(start -0.7874 0.4064)
			(end -0.7874 -0.4064)
			(stroke
				(width 0.1524)
				(type default)
			)
			(layer "F.SilkS")
		)
		(fp_line
			(start 0.7874 0.4064)
			(end -0.7874 0.4064)
			(stroke
				(width 0.1524)
				(type default)
			)
			(layer "F.SilkS")
		)
		(fp_line
			(start -0.7874 -0.4064)
			(end 0.7874 -0.4064)
			(stroke
				(width 0.1524)
				(type default)
			)
			(layer "F.SilkS")
		)
		(fp_line
			(start 0.7874 -0.4064)
			(end 0.7874 0.4064)
			(stroke
				(width 0.1524)
				(type default)
			)
			(layer "F.SilkS")
		)
		(fp_line
			(start -0.67945 0.3048)
			(end -0.67945 -0.305054)
			(stroke
				(width 0.1)
				(type default)
			)
			(layer "F.Fab")
		)
		(fp_line
			(start -0.12065 0.3048)
			(end -0.67945 0.3048)
			(stroke
				(width 0.1)
				(type default)
			)
			(layer "F.Fab")
		)
		(fp_line
			(start 0.120396 0.3048)
			(end 0.120396 0.2794)
			(stroke
				(width 0.1)
				(type default)
			)
			(layer "F.Fab")
		)
		(fp_line
			(start 0.67945 0.3048)
			(end 0.120396 0.3048)
			(stroke
				(width 0.1)
				(type default)
			)
			(layer "F.Fab")
		)
		(fp_line
			(start -0.12065 0.2794)
			(end -0.12065 0.3048)
			(stroke
				(width 0.1)
				(type default)
			)
			(layer "F.Fab")
		)
		(fp_line
			(start 0.120396 0.2794)
			(end -0.12065 0.2794)
			(stroke
				(width 0.1)
				(type default)
			)
			(layer "F.Fab")
		)
		(fp_line
			(start -0.12065 -0.2794)
			(end 0.12065 -0.2794)
			(stroke
				(width 0.1)
				(type default)
			)
			(layer "F.Fab")
		)
		(fp_line
			(start 0.12065 -0.2794)
			(end 0.12065 -0.3048)
			(stroke
				(width 0.1)
				(type default)
			)
			(layer "F.Fab")
		)
		(fp_line
			(start 0.12065 -0.3048)
			(end 0.67945 -0.3048)
			(stroke
				(width 0.1)
				(type default)
			)
			(layer "F.Fab")
		)
		(fp_line
			(start 0.67945 -0.3048)
			(end 0.67945 0.3048)
			(stroke
				(width 0.1)
				(type default)
			)
			(layer "F.Fab")
		)
		(fp_line
			(start -0.67945 -0.305054)
			(end -0.12065 -0.305054)
			(stroke
				(width 0.1)
				(type default)
			)
			(layer "F.Fab")
		)
		(fp_line
			(start -0.12065 -0.305054)
			(end -0.12065 -0.2794)
			(stroke
				(width 0.1)
				(type default)
			)
			(layer "F.Fab")
		)
		(pad "1" smd circle
			(at -0.40005 0 270)
			(size 0 0)
			(layers "F.Cu" "F.Mask" "F.Paste")
			(net "USB_HUB_XTAL_OUT")
		)
		(pad "2" smd circle
			(at 0.40005 0 270)
			(size 0 0)
			(layers "F.Cu" "F.Mask" "F.Paste")
			(net "GND")
		)
	)
)
